# S9S_MB_2U (Grand Teton) — schematic netlist excerpt (pin names and nets, part order shuffled) for the footprints in the layout excerpt that follows; sources: Cadence DE-HDL packaged netlist, KiCad conversion of 03242023_DA0F0TMBIJ0_F0T_Motherboard_J_brd_V01_OCP.brd

R2656  Q_RES  100 1% EMPTY  pkg 0402LF  page 144 : A = HGX_DETECT_N_ISO ; B = GND

DB8  TDR_3P  EMPTY  pkg TH2  page 309
  GND  = T1_GND
  IO1  = TDR_SE_50_OHM_IN1
  IO2  = TDR_SE_50_OHM_IN1

R1840  Q_RES  0 5% EMPTY  pkg 0402LF  page 185 : A = RST_PFR_OVR_SRTC ; B = RST_SRTCRST_N

(kicad_pcb
	(version 20260206)
	(generator "pcbnew")
	(generator_version "10.0")
	(general
		(thickness 1.6)
		(legacy_teardrops no)
	)
	(paper "A4")
	(title_block
		(title "03242023_DA0F0TMBIJ0_F0T_Motherboard_J_brd_V01_OCP.brd")
		(comment 1 "Grand Teton / footprints 2309-2311 of 6105")
	)
	(layers
		(0 "F.Cu" signal "TOP")
		(4 "In1.Cu" signal "GND")
		(6 "In2.Cu" signal "IN1")
		(8 "In3.Cu" signal "GND1")
		(10 "In4.Cu" signal "IN2")
		(12 "In5.Cu" signal "GND2")
		(14 "In6.Cu" signal "IN3")
		(16 "In7.Cu" signal "GND3")
		(18 "In8.Cu" signal "VCC")
		(20 "In9.Cu" signal "VCC1")
		(22 "In10.Cu" signal "GND4")
		(24 "In11.Cu" signal "IN4")
		(26 "In12.Cu" signal "GND5")
		(28 "In13.Cu" signal "IN5")
		(30 "In14.Cu" signal "GND6")
		(32 "In15.Cu" signal "IN6")
		(34 "In16.Cu" signal "GND7")
		(2 "B.Cu" signal "BOTTOM")
		(9 "F.Adhes" user "F.Adhesive")
		(11 "B.Adhes" user "B.Adhesive")
		(13 "F.Paste" user "Package Geometry/Pastemask Top")
		(15 "B.Paste" user "Package Geometry/Pastemask Bottom")
		(5 "F.SilkS" user "Ref Des/Silkscreen Top")
		(7 "B.SilkS" user "Ref Des/Silkscreen Bottom")
		(1 "F.Mask" user "Board Geometry/Soldermask Top")
		(3 "B.Mask" user "Board Geometry/Soldermask Bottom")
		(17 "Dwgs.User" user "User.Drawings")
		(19 "Cmts.User" user "User.Comments")
		(21 "Eco1.User" user "User.Eco1")
		(23 "Eco2.User" user "User.Eco2")
		(25 "Edge.Cuts" user "Board Geometry/Outline")
		(27 "Margin" user)
		(31 "F.CrtYd" user "Package Geometry/Place Bound Top")
		(29 "B.CrtYd" user "Package Geometry/Place Bound Bottom")
		(35 "F.Fab" user "Ref Des/Assembly Top")
		(33 "B.Fab" user "Ref Des/Assembly Bottom")
	)
	(footprint ""
		(layer "F.Cu")
		(at 203.326492 -105.315004 -90)
		(property "Reference" "R1840"
			(at 0 0 270)
			(layer "F.SilkS")
			(hide yes)
			(effects
				(font
					(size 1.27 1.27)
				)
			)
		)
		(property "Value" ""
			(at 0 0 270)
			(layer "F.Fab")
			(effects
				(font
					(size 1.27 1.27)
				)
			)
		)
		(duplicate_pad_numbers_are_jumpers no)
		(fp_line
			(start -0.7874 0.4064)
			(end -0.7874 -0.4064)
			(stroke
				(width 0.1524)
				(type default)
			)
			(layer "F.SilkS")
		)
		(fp_line
			(start 0.7874 0.4064)
			(end -0.7874 0.4064)
			(stroke
				(width 0.1524)
				(type default)
			)
			(layer "F.SilkS")
		)
		(fp_line
			(start -0.7874 -0.4064)
			(end 0.7874 -0.4064)
			(stroke
				(width 0.1524)
				(type default)
			)
			(layer "F.SilkS")
		)
		(fp_line
			(start 0.7874 -0.4064)
			(end 0.7874 0.4064)
			(stroke
				(width 0.1524)
				(type default)
			)
			(layer "F.SilkS")
		)
		(fp_line
			(start -0.67945 0.3048)
			(end -0.67945 -0.305054)
			(stroke
				(width 0.1)
				(type default)
			)
			(layer "F.Fab")
		)
		(fp_line
			(start -0.12065 0.3048)
			(end -0.67945 0.3048)
			(stroke
				(width 0.1)
				(type default)
			)
			(layer "F.Fab")
		)
		(fp_line
			(start 0.120396 0.3048)
			(end 0.120396 0.2794)
			(stroke
				(width 0.1)
				(type default)
			)
			(layer "F.Fab")
		)
		(fp_line
			(start 0.67945 0.3048)
			(end 0.120396 0.3048)
			(stroke
				(width 0.1)
				(type default)
			)
			(layer "F.Fab")
		)
		(fp_line
			(start -0.12065 0.2794)
			(end -0.12065 0.3048)
			(stroke
				(width 0.1)
				(type default)
			)
			(layer "F.Fab")
		)
		(fp_line
			(start 0.120396 0.2794)
			(end -0.12065 0.2794)
			(stroke
				(width 0.1)
				(type default)
			)
			(layer "F.Fab")
		)
		(fp_line
			(start -0.12065 -0.2794)
			(end 0.12065 -0.2794)
			(stroke
				(width 0.1)
				(type default)
			)
			(layer "F.Fab")
		)
		(fp_line
			(start 0.12065 -0.2794)
			(end 0.12065 -0.3048)
			(stroke
				(width 0.1)
				(type default)
			)
			(layer "F.Fab")
		)
		(fp_line
			(start 0.12065 -0.3048)
			(end 0.67945 -0.3048)
			(stroke
				(width 0.1)
				(type default)
			)
			(layer "F.Fab")
		)
		(fp_line
			(start 0.67945 -0.3048)
			(end 0.67945 0.3048)
			(stroke
				(width 0.1)
				(type default)
			)
			(layer "F.Fab")
		)
		(fp_line
			(start -0.67945 -0.305054)
			(end -0.12065 -0.305054)
			(stroke
				(width 0.1)
				(type default)
			)
			(layer "F.Fab")
		)
		(fp_line
			(start -0.12065 -0.305054)
			(end -0.12065 -0.2794)
			(stroke
				(width 0.1)
				(type default)
			)
			(layer "F.Fab")
		)
		(pad "1" smd circle
			(at -0.40005 0 270)
			(size 0 0)
			(layers "F.Cu" "F.Mask" "F.Paste")
			(net "RST_PFR_OVR_SRTC")
		)
		(pad "2" smd circle
			(at 0.40005 0 270)
			(size 0 0)
			(layers "F.Cu" "F.Mask" "F.Paste")
			(net "RST_SRTCRST_N")
		)
	)
	(footprint ""
		(layer "F.Cu")
		(at 483.210108 -427.547024 180)
		(property "Reference" "DB8"
			(at -2.931668 -0.465836 90)
			(unlocked yes)
			(layer "F.SilkS")
			(effects
				(font
					(size 0.7874 0.5842)
					(thickness 0.1524)
				)
				(justify left)
			)
		)
		(property "Value" ""
			(at 0 0 180)
			(layer "F.Fab")
			(effects
				(font
					(size 1.27 1.27)
				)
			)
		)
		(duplicate_pad_numbers_are_jumpers no)
		(fp_line
			(start 2.71653 -3.151378)
			(end 0 4.011168)
			(stroke
				(width 0.1524)
				(type default)
			)
			(layer "F.SilkS")
		)
		(fp_line
			(start 0 4.011168)
			(end -3.330702 -4.771136)
			(stroke
				(width 0.1524)
				(type default)
			)
			(layer "F.SilkS")
		)
		(fp_line
			(start -3.330702 -4.771136)
			(end 3.330702 -4.771136)
			(stroke
				(width 0.1524)
				(type default)
			)
			(layer "F.SilkS")
		)
		(fp_line
			(start 3.330702 -4.771136)
			(end 0 4.011168)
			(stroke
				(width 0.1)
				(type default)
			)
			(layer "F.Fab")
		)
		(fp_line
			(start 0 4.011168)
			(end -3.330702 -4.771136)
			(stroke
				(width 0.1)
				(type default)
			)
			(layer "F.Fab")
		)
		(fp_line
			(start -3.330702 -4.771136)
			(end 3.330702 -4.771136)
			(stroke
				(width 0.1)
				(type default)
			)
			(layer "F.Fab")
		)
		(pad "1" thru_hole circle
			(at 0 0 180)
			(size 2.159 2.159)
			(drill 1.7018)
			(layers "*.Cu" "*.Mask")
			(remove_unused_layers no)
			(net "T1_GND")
			(clearance 0.0254)
			(thermal_gap 0.0254)
		)
		(pad "2" thru_hole circle
			(at -1.27 -3.348736 180)
			(size 2.159 2.159)
			(drill 1.7018)
			(layers "*.Cu" "*.Mask")
			(remove_unused_layers no)
			(net "TDR_SE_50_OHM_IN1")
			(clearance 0.0254)
			(thermal_gap 0.0254)
		)
		(pad "3" thru_hole circle
			(at 1.27 -3.348736 180)
			(size 2.159 2.159)
			(drill 1.7018)
			(layers "*.Cu" "*.Mask")
			(remove_unused_layers no)
			(net "TDR_SE_50_OHM_IN1")
			(clearance 0.0254)
			(thermal_gap 0.0254)
		)
	)
	(footprint ""
		(layer "F.Cu")
		(at 44.905422 -401.567396 90)
		(property "Reference" "R2656"
			(at 0 0 90)
			(layer "F.SilkS")
			(hide yes)
			(effects
				(font
					(size 1.27 1.27)
				)
			)
		)
		(property "Value" ""
			(at 0 0 90)
			(layer "F.Fab")
			(effects
				(font
					(size 1.27 1.27)
				)
			)
		)
		(duplicate_pad_numbers_are_jumpers no)
		(fp_line
			(start 0.7874 -0.4064)
			(end 0.7874 0.4064)
			(stroke
				(width 0.1524)
				(type default)
			)
			(layer "F.SilkS")
		)
		(fp_line
			(start -0.7874 -0.4064)
			(end 0.7874 -0.4064)
			(stroke
				(width 0.1524)
				(type default)
			)
			(layer "F.SilkS")
		)
		(fp_line
			(start 0.7874 0.4064)
			(end -0.7874 0.4064)
			(stroke
				(width 0.1524)
				(type default)
			)
			(layer "F.SilkS")
		)
		(fp_line
			(start -0.7874 0.4064)
			(end -0.7874 -0.4064)
			(stroke
				(width 0.1524)
				(type default)
			)
			(layer "F.SilkS")
		)
		(fp_line
			(start -0.12065 -0.305054)
			(end -0.12065 -0.2794)
			(stroke
				(width 0.1)
				(type default)
			)
			(layer "F.Fab")
		)
		(fp_line
			(start -0.67945 -0.305054)
			(end -0.12065 -0.305054)
			(stroke
				(width 0.1)
				(type default)
			)
			(layer "F.Fab")
		)
		(fp_line
			(start 0.67945 -0.3048)
			(end 0.67945 0.3048)
			(stroke
				(width 0.1)
				(type default)
			)
			(layer "F.Fab")
		)
		(fp_line
			(start 0.12065 -0.3048)
			(end 0.67945 -0.3048)
			(stroke
				(width 0.1)
				(type default)
			)
			(layer "F.Fab")
		)
		(fp_line
			(start 0.12065 -0.2794)
			(end 0.12065 -0.3048)
			(stroke
				(width 0.1)
				(type default)
			)
			(layer "F.Fab")
		)
		(fp_line
			(start -0.12065 -0.2794)
			(end 0.12065 -0.2794)
			(stroke
				(width 0.1)
				(type default)
			)
			(layer "F.Fab")
		)
		(fp_line
			(start 0.120396 0.2794)
			(end -0.12065 0.2794)
			(stroke
				(width 0.1)
				(type default)
			)
			(layer "F.Fab")
		)
		(fp_line
			(start -0.12065 0.2794)
			(end -0.12065 0.3048)
			(stroke
				(width 0.1)
				(type default)
			)
			(layer "F.Fab")
		)
		(fp_line
			(start 0.67945 0.3048)
			(end 0.120396 0.3048)
			(stroke
				(width 0.1)
				(type default)
			)
			(layer "F.Fab")
		)
		(fp_line
			(start 0.120396 0.3048)
			(end 0.120396 0.2794)
			(stroke
				(width 0.1)
				(type default)
			)
			(layer "F.Fab")
		)
		(fp_line
			(start -0.12065 0.3048)
			(end -0.67945 0.3048)
			(stroke
				(width 0.1)
				(type default)
			)
			(layer "F.Fab")
		)
		(fp_line
			(start -0.67945 0.3048)
			(end -0.67945 -0.305054)
			(stroke
				(width 0.1)
				(type default)
			)
			(layer "F.Fab")
		)
		(pad "1" smd circle
			(at -0.40005 0 90)
			(size 0 0)
			(layers "F.Cu" "F.Mask" "F.Paste")
			(net "HGX_DETECT_N_ISO")
		)
		(pad "2" smd circle
			(at 0.40005 0 90)
			(size 0 0)
			(layers "F.Cu" "F.Mask" "F.Paste")
			(net "GND")
		)
	)
)
